FILE_TYPE = MULTI_PHYS_TABLE;

PART 'TPS54824RNVR_VQFN18'
CLASS = IC 

{========================================================================================}
: CLS_PN          | VALUE            =  JEDEC_TYPE                       | ALT_SYMBOLS                           | DESCRIPTION                 | CPN_STATUS ;
{========================================================================================}
 'G220-10645-01'  |'TPS54824RNVR' (!)  = 'QFN18_138_P0197_V1'  |'(QFN18_138_P0197_V1)'  |'IC,TPS54824RNVR,4.5V-17V INPUT 8A DC-DC CONVERTER,QFN 18' | ''
 'G220-10657-01'  |'TPS54424RNVT' (!)  = 'QFN18_138_P0197_V1'  |'(QFN18_138_P0197_V1)'  |'IC,TPS54424RNVT,4.5V-17V INPUT 4A DC-DC CONVERTER,QFN 18' | ''

END_PART

END.

